(kicad_pcb
	(version 20260206)
	(generator "pcbnew")
	(generator_version "10.0")
	(general
		(thickness 1.6)
		(legacy_teardrops no)
	)
	(paper "A4")
	(title_block
		(title "Bryce Canyon_IOM_M2_16342-2_OCP.brd")
		(comment 1 "Bryce Canyon / footprints 1005-1011 of 1146")
	)
	(layers
		(0 "F.Cu" signal "TOP")
		(4 "In1.Cu" signal "L2GND")
		(6 "In2.Cu" signal "L3")
		(8 "In3.Cu" signal "L4VCC")
		(10 "In4.Cu" signal "L5VCC")
		(12 "In5.Cu" signal "L6")
		(14 "In6.Cu" signal "L7GND")
		(2 "B.Cu" signal "BOTTOM")
		(9 "F.Adhes" user "F.Adhesive")
		(11 "B.Adhes" user "B.Adhesive")
		(13 "F.Paste" user "Package Geometry/Pastemask Top")
		(15 "B.Paste" user "Package Geometry/Pastemask Bottom")
		(5 "F.SilkS" user "Ref Des/Silkscreen Top")
		(7 "B.SilkS" user "Ref Des/Silkscreen Bottom")
		(1 "F.Mask" user "Board Geometry/Soldermask Top")
		(3 "B.Mask" user "Board Geometry/Soldermask Bottom")
		(17 "Dwgs.User" user "User.Drawings")
		(19 "Cmts.User" user "User.Comments")
		(21 "Eco1.User" user "User.Eco1")
		(23 "Eco2.User" user "User.Eco2")
		(25 "Edge.Cuts" user "Board Geometry/Outline")
		(27 "Margin" user)
		(31 "F.CrtYd" user "Package Geometry/Place Bound Top")
		(29 "B.CrtYd" user "Package Geometry/Place Bound Bottom")
		(35 "F.Fab" user "Ref Des/Assembly Top")
		(33 "B.Fab" user "Ref Des/Assembly Bottom")
	)
	(footprint ""
		(layer "B.Cu")
		(at 37.9222 -157.5308 -90)
		(property "Reference" "R700"
			(at 0 0 90)
			(layer "B.SilkS")
			(hide yes)
			(effects
				(font
					(size 1.27 1.27)
				)
				(justify mirror)
			)
		)
		(property "Value" "4K7R2F-GP"
			(at -0.064008 -3.993896 270)
			(unlocked yes)
			(layer "B.Fab")
			(hide yes)
			(effects
				(font
					(size 1.016 1.016)
					(thickness 0.1524)
				)
				(justify mirror)
			)
		)
		(property "Device Type" "R402H16"
			(at -0.064008 -5.517896 270)
			(unlocked yes)
			(layer "B.Fab")
			(hide yes)
			(effects
				(font
					(size 1.016 1.016)
					(thickness 0.1524)
				)
				(justify mirror)
			)
		)
		(duplicate_pad_numbers_are_jumpers no)
		(fp_line
			(start -0.508 -0.9398)
			(end 0.508 -0.9398)
			(stroke
				(width 0.1524)
				(type default)
			)
			(layer "B.SilkS")
		)
		(fp_line
			(start 0.508 -0.9398)
			(end 0.508 0.9398)
			(stroke
				(width 0.1524)
				(type default)
			)
			(layer "B.SilkS")
		)
		(fp_rect
			(start 0.508 0.9398)
			(end -0.508 -0.9398)
			(stroke
				(width 0)
				(type default)
			)
			(fill no)
			(layer "B.CrtYd")
		)
		(fp_rect
			(start 0.508 0.9398)
			(end -0.508 -0.9398)
			(stroke
				(width 0)
				(type default)
			)
			(fill no)
			(layer "B.Fab")
		)
		(pad "1" smd custom
			(at 0 -0.4445 90)
			(size 0.1397 0.1397)
			(layers "B.Cu" "B.Mask" "B.Paste")
			(net "P3V3_STBY")
			(options
				(clearance outline)
				(anchor circle)
			)
			(primitives
				(gr_poly
					(pts
						(arc
							(start -0.1778 0.2794)
							(mid -0.249642 0.249642)
							(end -0.2794 0.1778)
						)
						(arc
							(start -0.2794 -0.1778)
							(mid -0.249642 -0.249642)
							(end -0.1778 -0.2794)
						)
						(arc
							(start 0.1778 -0.2794)
							(mid 0.249642 -0.249642)
							(end 0.2794 -0.1778)
						)
						(arc
							(start 0.2794 0.1778)
							(mid 0.249642 0.249642)
							(end 0.1778 0.2794)
						)
					)
					(width 0)
					(fill yes)
				)
			)
		)
		(pad "2" smd custom
			(at 0 0.4445 90)
			(size 0.1397 0.1397)
			(layers "B.Cu" "B.Mask" "B.Paste")
			(net "IOM_TYPE3")
			(options
				(clearance outline)
				(anchor circle)
			)
			(primitives
				(gr_poly
					(pts
						(arc
							(start -0.1778 0.2794)
							(mid -0.249642 0.249642)
							(end -0.2794 0.1778)
						)
						(arc
							(start -0.2794 -0.1778)
							(mid -0.249642 -0.249642)
							(end -0.1778 -0.2794)
						)
						(arc
							(start 0.1778 -0.2794)
							(mid 0.249642 -0.249642)
							(end 0.2794 -0.1778)
						)
						(arc
							(start 0.2794 0.1778)
							(mid 0.249642 0.249642)
							(end 0.1778 0.2794)
						)
					)
					(width 0)
					(fill yes)
				)
			)
		)
	)
	(footprint ""
		(layer "B.Cu")
		(at 54.723792 -135.610854 180)
		(property "Reference" "R353"
			(at 0 0 0)
			(layer "B.SilkS")
			(hide yes)
			(effects
				(font
					(size 1.27 1.27)
				)
				(justify mirror)
			)
		)
		(property "Value" "4K7R2F-GP"
			(at -0.064008 -3.993896 180)
			(unlocked yes)
			(layer "B.Fab")
			(hide yes)
			(effects
				(font
					(size 1.016 1.016)
					(thickness 0.1524)
				)
				(justify mirror)
			)
		)
		(property "Device Type" "R402H16"
			(at -0.064008 -5.517896 180)
			(unlocked yes)
			(layer "B.Fab")
			(hide yes)
			(effects
				(font
					(size 1.016 1.016)
					(thickness 0.1524)
				)
				(justify mirror)
			)
		)
		(duplicate_pad_numbers_are_jumpers no)
		(fp_line
			(start 0.508 -0.9398)
			(end 0.508 0.9398)
			(stroke
				(width 0.1524)
				(type default)
			)
			(layer "B.SilkS")
		)
		(fp_line
			(start -0.508 -0.9398)
			(end 0.508 -0.9398)
			(stroke
				(width 0.1524)
				(type default)
			)
			(layer "B.SilkS")
		)
		(fp_rect
			(start 0.508 0.9398)
			(end -0.508 -0.9398)
			(stroke
				(width 0)
				(type default)
			)
			(fill no)
			(layer "B.CrtYd")
		)
		(fp_rect
			(start 0.508 0.9398)
			(end -0.508 -0.9398)
			(stroke
				(width 0)
				(type default)
			)
			(fill no)
			(layer "B.Fab")
		)
		(pad "1" smd custom
			(at 0 -0.4445)
			(size 0.1397 0.1397)
			(layers "B.Cu" "B.Mask" "B.Paste")
			(net "P3V3_STBY")
			(options
				(clearance outline)
				(anchor circle)
			)
			(primitives
				(gr_poly
					(pts
						(arc
							(start -0.1778 0.2794)
							(mid -0.249642 0.249642)
							(end -0.2794 0.1778)
						)
						(arc
							(start -0.2794 -0.1778)
							(mid -0.249642 -0.249642)
							(end -0.1778 -0.2794)
						)
						(arc
							(start 0.1778 -0.2794)
							(mid 0.249642 -0.249642)
							(end 0.2794 -0.1778)
						)
						(arc
							(start 0.2794 0.1778)
							(mid 0.249642 0.249642)
							(end 0.1778 0.2794)
						)
					)
					(width 0)
					(fill yes)
				)
			)
		)
		(pad "2" smd custom
			(at 0 0.4445)
			(size 0.1397 0.1397)
			(layers "B.Cu" "B.Mask" "B.Paste")
			(net "SLOTID_1")
			(options
				(clearance outline)
				(anchor circle)
			)
			(primitives
				(gr_poly
					(pts
						(arc
							(start -0.1778 0.2794)
							(mid -0.249642 0.249642)
							(end -0.2794 0.1778)
						)
						(arc
							(start -0.2794 -0.1778)
							(mid -0.249642 -0.249642)
							(end -0.1778 -0.2794)
						)
						(arc
							(start 0.1778 -0.2794)
							(mid 0.249642 -0.249642)
							(end 0.2794 -0.1778)
						)
						(arc
							(start 0.2794 0.1778)
							(mid 0.249642 0.249642)
							(end 0.1778 0.2794)
						)
					)
					(width 0)
					(fill yes)
				)
			)
		)
	)
	(footprint ""
		(layer "B.Cu")
		(at 38.443154 -127.888238)
		(property "Reference" "R732"
			(at 0 0 0)
			(layer "B.SilkS")
			(hide yes)
			(effects
				(font
					(size 1.27 1.27)
				)
				(justify mirror)
			)
		)
		(property "Value" "0R2J-2-GP"
			(at -0.064008 -3.993896 0)
			(unlocked yes)
			(layer "B.Fab")
			(hide yes)
			(effects
				(font
					(size 1.016 1.016)
					(thickness 0.1524)
				)
				(justify mirror)
			)
		)
		(property "Device Type" "R402H16"
			(at -0.064008 -5.517896 0)
			(unlocked yes)
			(layer "B.Fab")
			(hide yes)
			(effects
				(font
					(size 1.016 1.016)
					(thickness 0.1524)
				)
				(justify mirror)
			)
		)
		(duplicate_pad_numbers_are_jumpers no)
		(fp_line
			(start -0.508 -0.9398)
			(end 0.508 -0.9398)
			(stroke
				(width 0.1524)
				(type default)
			)
			(layer "B.SilkS")
		)
		(fp_line
			(start 0.508 -0.9398)
			(end 0.508 0.9398)
			(stroke
				(width 0.1524)
				(type default)
			)
			(layer "B.SilkS")
		)
		(fp_rect
			(start 0.508 0.9398)
			(end -0.508 -0.9398)
			(stroke
				(width 0)
				(type default)
			)
			(fill no)
			(layer "B.CrtYd")
		)
		(fp_rect
			(start 0.508 0.9398)
			(end -0.508 -0.9398)
			(stroke
				(width 0)
				(type default)
			)
			(fill no)
			(layer "B.Fab")
		)
		(pad "1" smd custom
			(at 0 -0.4445 180)
			(size 0.1397 0.1397)
			(layers "B.Cu" "B.Mask" "B.Paste")
			(net "U104_EN")
			(options
				(clearance outline)
				(anchor circle)
			)
			(primitives
				(gr_poly
					(pts
						(arc
							(start -0.1778 0.2794)
							(mid -0.249642 0.249642)
							(end -0.2794 0.1778)
						)
						(arc
							(start -0.2794 -0.1778)
							(mid -0.249642 -0.249642)
							(end -0.1778 -0.2794)
						)
						(arc
							(start 0.1778 -0.2794)
							(mid 0.249642 -0.249642)
							(end 0.2794 -0.1778)
						)
						(arc
							(start 0.2794 0.1778)
							(mid 0.249642 0.249642)
							(end 0.1778 0.2794)
						)
					)
					(width 0)
					(fill yes)
				)
			)
		)
		(pad "2" smd custom
			(at 0 0.4445 180)
			(size 0.1397 0.1397)
			(layers "B.Cu" "B.Mask" "B.Paste")
			(net "COMP_PWR_EN")
			(options
				(clearance outline)
				(anchor circle)
			)
			(primitives
				(gr_poly
					(pts
						(arc
							(start -0.1778 0.2794)
							(mid -0.249642 0.249642)
							(end -0.2794 0.1778)
						)
						(arc
							(start -0.2794 -0.1778)
							(mid -0.249642 -0.249642)
							(end -0.1778 -0.2794)
						)
						(arc
							(start 0.1778 -0.2794)
							(mid 0.249642 -0.249642)
							(end 0.2794 -0.1778)
						)
						(arc
							(start 0.2794 0.1778)
							(mid 0.249642 0.249642)
							(end 0.1778 0.2794)
						)
					)
					(width 0)
					(fill yes)
				)
			)
		)
	)
	(footprint ""
		(layer "B.Cu")
		(at 74.88428 -142.525242 90)
		(property "Reference" "R385"
			(at 0 0 90)
			(layer "B.SilkS")
			(hide yes)
			(effects
				(font
					(size 1.27 1.27)
				)
				(justify mirror)
			)
		)
		(property "Value" "4K7R2F-GP"
			(at -0.064008 -3.993896 90)
			(unlocked yes)
			(layer "B.Fab")
			(hide yes)
			(effects
				(font
					(size 1.016 1.016)
					(thickness 0.1524)
				)
				(justify mirror)
			)
		)
		(property "Device Type" "R402H16"
			(at -0.064008 -5.517896 90)
			(unlocked yes)
			(layer "B.Fab")
			(hide yes)
			(effects
				(font
					(size 1.016 1.016)
					(thickness 0.1524)
				)
				(justify mirror)
			)
		)
		(duplicate_pad_numbers_are_jumpers no)
		(fp_line
			(start 0.508 -0.9398)
			(end 0.508 0.9398)
			(stroke
				(width 0.1524)
				(type default)
			)
			(layer "B.SilkS")
		)
		(fp_line
			(start -0.508 -0.9398)
			(end 0.508 -0.9398)
			(stroke
				(width 0.1524)
				(type default)
			)
			(layer "B.SilkS")
		)
		(fp_rect
			(start 0.508 0.9398)
			(end -0.508 -0.9398)
			(stroke
				(width 0)
				(type default)
			)
			(fill no)
			(layer "B.CrtYd")
		)
		(fp_rect
			(start 0.508 0.9398)
			(end -0.508 -0.9398)
			(stroke
				(width 0)
				(type default)
			)
			(fill no)
			(layer "B.Fab")
		)
		(pad "1" smd custom
			(at 0 -0.4445 270)
			(size 0.1397 0.1397)
			(layers "B.Cu" "B.Mask" "B.Paste")
			(net "GND")
			(options
				(clearance outline)
				(anchor circle)
			)
			(primitives
				(gr_poly
					(pts
						(arc
							(start -0.1778 0.2794)
							(mid -0.249642 0.249642)
							(end -0.2794 0.1778)
						)
						(arc
							(start -0.2794 -0.1778)
							(mid -0.249642 -0.249642)
							(end -0.1778 -0.2794)
						)
						(arc
							(start 0.1778 -0.2794)
							(mid 0.249642 -0.249642)
							(end 0.2794 -0.1778)
						)
						(arc
							(start 0.2794 0.1778)
							(mid 0.249642 0.249642)
							(end 0.1778 0.2794)
						)
					)
					(width 0)
					(fill yes)
				)
			)
		)
		(pad "2" smd custom
			(at 0 0.4445 270)
			(size 0.1397 0.1397)
			(layers "B.Cu" "B.Mask" "B.Paste")
			(net "NCSI_TXEN")
			(options
				(clearance outline)
				(anchor circle)
			)
			(primitives
				(gr_poly
					(pts
						(arc
							(start -0.1778 0.2794)
							(mid -0.249642 0.249642)
							(end -0.2794 0.1778)
						)
						(arc
							(start -0.2794 -0.1778)
							(mid -0.249642 -0.249642)
							(end -0.1778 -0.2794)
						)
						(arc
							(start 0.1778 -0.2794)
							(mid 0.249642 -0.249642)
							(end 0.2794 -0.1778)
						)
						(arc
							(start 0.2794 0.1778)
							(mid 0.249642 0.249642)
							(end 0.1778 0.2794)
						)
					)
					(width 0)
					(fill yes)
				)
			)
		)
	)
	(footprint ""
		(layer "B.Cu")
		(at 52.648612 -135.661654)
		(property "Reference" "R167"
			(at 0 0 0)
			(layer "B.SilkS")
			(hide yes)
			(effects
				(font
					(size 1.27 1.27)
				)
				(justify mirror)
			)
		)
		(property "Value" "0R2J-2-GP"
			(at -0.064008 -3.993896 0)
			(unlocked yes)
			(layer "B.Fab")
			(hide yes)
			(effects
				(font
					(size 1.016 1.016)
					(thickness 0.1524)
				)
				(justify mirror)
			)
		)
		(property "Device Type" "R402H16"
			(at -0.064008 -5.517896 0)
			(unlocked yes)
			(layer "B.Fab")
			(hide yes)
			(effects
				(font
					(size 1.016 1.016)
					(thickness 0.1524)
				)
				(justify mirror)
			)
		)
		(duplicate_pad_numbers_are_jumpers no)
		(fp_line
			(start -0.508 -0.9398)
			(end 0.508 -0.9398)
			(stroke
				(width 0.1524)
				(type default)
			)
			(layer "B.SilkS")
		)
		(fp_line
			(start 0.508 -0.9398)
			(end 0.508 0.9398)
			(stroke
				(width 0.1524)
				(type default)
			)
			(layer "B.SilkS")
		)
		(fp_rect
			(start 0.508 0.9398)
			(end -0.508 -0.9398)
			(stroke
				(width 0)
				(type default)
			)
			(fill no)
			(layer "B.CrtYd")
		)
		(fp_rect
			(start 0.508 0.9398)
			(end -0.508 -0.9398)
			(stroke
				(width 0)
				(type default)
			)
			(fill no)
			(layer "B.Fab")
		)
		(pad "1" smd custom
			(at 0 -0.4445 180)
			(size 0.1397 0.1397)
			(layers "B.Cu" "B.Mask" "B.Paste")
			(net "PWRBTN_OUT_N_R")
			(options
				(clearance outline)
				(anchor circle)
			)
			(primitives
				(gr_poly
					(pts
						(arc
							(start -0.1778 0.2794)
							(mid -0.249642 0.249642)
							(end -0.2794 0.1778)
						)
						(arc
							(start -0.2794 -0.1778)
							(mid -0.249642 -0.249642)
							(end -0.1778 -0.2794)
						)
						(arc
							(start 0.1778 -0.2794)
							(mid 0.249642 -0.249642)
							(end 0.2794 -0.1778)
						)
						(arc
							(start 0.2794 0.1778)
							(mid 0.249642 0.249642)
							(end 0.1778 0.2794)
						)
					)
					(width 0)
					(fill yes)
				)
			)
		)
		(pad "2" smd custom
			(at 0 0.4445 180)
			(size 0.1397 0.1397)
			(layers "B.Cu" "B.Mask" "B.Paste")
			(net "PWRBTN_OUT_N")
			(options
				(clearance outline)
				(anchor circle)
			)
			(primitives
				(gr_poly
					(pts
						(arc
							(start -0.1778 0.2794)
							(mid -0.249642 0.249642)
							(end -0.2794 0.1778)
						)
						(arc
							(start -0.2794 -0.1778)
							(mid -0.249642 -0.249642)
							(end -0.1778 -0.2794)
						)
						(arc
							(start 0.1778 -0.2794)
							(mid 0.249642 -0.249642)
							(end 0.2794 -0.1778)
						)
						(arc
							(start 0.2794 0.1778)
							(mid 0.249642 0.249642)
							(end 0.1778 0.2794)
						)
					)
					(width 0)
					(fill yes)
				)
			)
		)
	)
	(footprint ""
		(layer "B.Cu")
		(at 76.0984 -134.0866 90)
		(property "Reference" "C30"
			(at 0 0 90)
			(layer "B.SilkS")
			(hide yes)
			(effects
				(font
					(size 1.27 1.27)
				)
				(justify mirror)
			)
		)
		(property "Value" "SCD1U16V2KX-3GP"
			(at -1.1811 -2.7051 90)
			(unlocked yes)
			(layer "B.Fab")
			(hide yes)
			(effects
				(font
					(size 1.016 1.016)
					(thickness 0.1524)
				)
				(justify mirror)
			)
		)
		(property "Device Type" "C402H22"
			(at -1.1811 -4.2291 90)
			(unlocked yes)
			(layer "B.Fab")
			(hide yes)
			(effects
				(font
					(size 1.016 1.016)
					(thickness 0.1524)
				)
				(justify mirror)
			)
		)
		(duplicate_pad_numbers_are_jumpers no)
		(fp_rect
			(start 0.4318 0.9525)
			(end -0.4318 -0.9525)
			(stroke
				(width 0)
				(type default)
			)
			(fill no)
			(layer "B.CrtYd")
		)
		(fp_rect
			(start 0.4318 0.9525)
			(end -0.4318 -0.9525)
			(stroke
				(width 0)
				(type default)
			)
			(fill no)
			(layer "B.Fab")
		)
		(pad "1" smd custom
			(at 0 -0.4445 270)
			(size 0.1524 0.1524)
			(layers "B.Cu" "B.Mask" "B.Paste")
			(net "P3V3_STBY")
			(options
				(clearance outline)
				(anchor circle)
			)
			(primitives
				(gr_poly
					(pts
						(arc
							(start 0.3048 0.2032)
							(mid 0.275042 0.275042)
							(end 0.2032 0.3048)
						)
						(arc
							(start -0.2032 0.3048)
							(mid -0.275042 0.275042)
							(end -0.3048 0.2032)
						)
						(arc
							(start -0.3048 -0.2032)
							(mid -0.275042 -0.275042)
							(end -0.2032 -0.3048)
						)
						(arc
							(start 0.2032 -0.3048)
							(mid 0.275042 -0.275042)
							(end 0.3048 -0.2032)
						)
					)
					(width 0)
					(fill yes)
				)
			)
		)
		(pad "2" smd custom
			(at 0 0.4445 270)
			(size 0.1524 0.1524)
			(layers "B.Cu" "B.Mask" "B.Paste")
			(net "GND")
			(options
				(clearance outline)
				(anchor circle)
			)
			(primitives
				(gr_poly
					(pts
						(arc
							(start 0.3048 0.2032)
							(mid 0.275042 0.275042)
							(end 0.2032 0.3048)
						)
						(arc
							(start -0.2032 0.3048)
							(mid -0.275042 0.275042)
							(end -0.3048 0.2032)
						)
						(arc
							(start -0.3048 -0.2032)
							(mid -0.275042 -0.275042)
							(end -0.2032 -0.3048)
						)
						(arc
							(start 0.2032 -0.3048)
							(mid 0.275042 -0.275042)
							(end 0.3048 -0.2032)
						)
					)
					(width 0)
					(fill yes)
				)
			)
		)
	)
	(footprint ""
		(layer "B.Cu")
		(at 91.22029 -168.02227 -90)
		(property "Reference" "R419"
			(at 0 0 90)
			(layer "B.SilkS")
			(hide yes)
			(effects
				(font
					(size 1.27 1.27)
				)
				(justify mirror)
			)
		)
		(property "Value" "0R2J-2-GP"
			(at -0.064008 -3.993896 270)
			(unlocked yes)
			(layer "B.Fab")
			(hide yes)
			(effects
				(font
					(size 1.016 1.016)
					(thickness 0.1524)
				)
				(justify mirror)
			)
		)
		(property "Device Type" "R402H16"
			(at -0.064008 -5.517896 270)
			(unlocked yes)
			(layer "B.Fab")
			(hide yes)
			(effects
				(font
					(size 1.016 1.016)
					(thickness 0.1524)
				)
				(justify mirror)
			)
		)
		(duplicate_pad_numbers_are_jumpers no)
		(fp_line
			(start -0.508 -0.9398)
			(end 0.508 -0.9398)
			(stroke
				(width 0.1524)
				(type default)
			)
			(layer "B.SilkS")
		)
		(fp_line
			(start 0.508 -0.9398)
			(end 0.508 0.9398)
			(stroke
				(width 0.1524)
				(type default)
			)
			(layer "B.SilkS")
		)
		(fp_rect
			(start 0.508 0.9398)
			(end -0.508 -0.9398)
			(stroke
				(width 0)
				(type default)
			)
			(fill no)
			(layer "B.CrtYd")
		)
		(fp_rect
			(start 0.508 0.9398)
			(end -0.508 -0.9398)
			(stroke
				(width 0)
				(type default)
			)
			(fill no)
			(layer "B.Fab")
		)
		(pad "1" smd custom
			(at 0 -0.4445 90)
			(size 0.1397 0.1397)
			(layers "B.Cu" "B.Mask" "B.Paste")
			(net "UART_COMP_RX")
			(options
				(clearance outline)
				(anchor circle)
			)
			(primitives
				(gr_poly
					(pts
						(arc
							(start -0.1778 0.2794)
							(mid -0.249642 0.249642)
							(end -0.2794 0.1778)
						)
						(arc
							(start -0.2794 -0.1778)
							(mid -0.249642 -0.249642)
							(end -0.1778 -0.2794)
						)
						(arc
							(start 0.1778 -0.2794)
							(mid 0.249642 -0.249642)
							(end 0.2794 -0.1778)
						)
						(arc
							(start 0.2794 0.1778)
							(mid 0.249642 0.249642)
							(end 0.1778 0.2794)
						)
					)
					(width 0)
					(fill yes)
				)
			)
		)
		(pad "2" smd custom
			(at 0 0.4445 90)
			(size 0.1397 0.1397)
			(layers "B.Cu" "B.Mask" "B.Paste")
			(net "UART_COMP_R_RX")
			(options
				(clearance outline)
				(anchor circle)
			)
			(primitives
				(gr_poly
					(pts
						(arc
							(start -0.1778 0.2794)
							(mid -0.249642 0.249642)
							(end -0.2794 0.1778)
						)
						(arc
							(start -0.2794 -0.1778)
							(mid -0.249642 -0.249642)
							(end -0.1778 -0.2794)
						)
						(arc
							(start 0.1778 -0.2794)
							(mid 0.249642 -0.249642)
							(end 0.2794 -0.1778)
						)
						(arc
							(start 0.2794 0.1778)
							(mid 0.249642 0.249642)
							(end 0.1778 0.2794)
						)
					)
					(width 0)
					(fill yes)
				)
			)
		)
	)
)
